# T6G (Grand Teton) — schematic netlist excerpt (pin names and nets, part order shuffled) for the footprints in the layout excerpt that follows; sources: Cadence DE-HDL packaged netlist, KiCad conversion of 04192023_DAF0TMB3IC0_F0TG_MB_C_brd_V02_OCP.brd

C9  Q_CAP  1UF 25V 10% EMPTY  pkg C0402  page 161 : A = I3C_MUX_CPU0_VIO ; B = GND

(kicad_pcb
	(version 20260206)
	(generator "pcbnew")
	(generator_version "10.0")
	(general
		(thickness 1.6)
		(legacy_teardrops no)
	)
	(paper "A4")
	(title_block
		(title "04192023_DAF0TMB3IC0_F0TG_MB_C_brd_V02_OCP.brd")
		(comment 1 "Grand Teton / footprints 5384-5384 of 8354")
	)
	(layers
		(0 "F.Cu" signal "TOP")
		(4 "In1.Cu" signal "GND")
		(6 "In2.Cu" signal "IN1")
		(8 "In3.Cu" signal "GND1")
		(10 "In4.Cu" signal "IN2")
		(12 "In5.Cu" signal "GND2")
		(14 "In6.Cu" signal "IN3")
		(16 "In7.Cu" signal "GND3")
		(18 "In8.Cu" signal "VCC")
		(20 "In9.Cu" signal "VCC1")
		(22 "In10.Cu" signal "GND4")
		(24 "In11.Cu" signal "IN4")
		(26 "In12.Cu" signal "GND5")
		(28 "In13.Cu" signal "IN5")
		(30 "In14.Cu" signal "GND6")
		(32 "In15.Cu" signal "IN6")
		(34 "In16.Cu" signal "GND7")
		(2 "B.Cu" signal "BOTTOM")
		(9 "F.Adhes" user "F.Adhesive")
		(11 "B.Adhes" user "B.Adhesive")
		(13 "F.Paste" user "Package Geometry/Pastemask Top")
		(15 "B.Paste" user "Package Geometry/Pastemask Bottom")
		(5 "F.SilkS" user "Ref Des/Silkscreen Top")
		(7 "B.SilkS" user "Ref Des/Silkscreen Bottom")
		(1 "F.Mask" user "Board Geometry/Soldermask Top")
		(3 "B.Mask" user "Board Geometry/Soldermask Bottom")
		(17 "Dwgs.User" user "User.Drawings")
		(19 "Cmts.User" user "User.Comments")
		(21 "Eco1.User" user "User.Eco1")
		(23 "Eco2.User" user "User.Eco2")
		(25 "Edge.Cuts" user "Board Geometry/Outline")
		(27 "Margin" user)
		(31 "F.CrtYd" user "Package Geometry/Place Bound Top")
		(29 "B.CrtYd" user "Package Geometry/Place Bound Bottom")
		(35 "F.Fab" user "Ref Des/Assembly Top")
		(33 "B.Fab" user "Ref Des/Assembly Bottom")
	)
	(footprint ""
		(layer "B.Cu")
		(at 230.886 -232.156 90)
		(property "Reference" "C9"
			(at 0 0 90)
			(layer "B.SilkS")
			(hide yes)
			(effects
				(font
					(size 1.27 1.27)
				)
				(justify mirror)
			)
		)
		(property "Value" ""
			(at 0 0 90)
			(layer "B.Fab")
			(effects
				(font
					(size 1.27 1.27)
				)
				(justify mirror)
			)
		)
		(duplicate_pad_numbers_are_jumpers no)
		(fp_line
			(start 0.7874 -0.4064)
			(end -0.7874 -0.4064)
			(stroke
				(width 0.1524)
				(type default)
			)
			(layer "B.SilkS")
		)
		(fp_line
			(start -0.7874 -0.4064)
			(end -0.7874 0.4064)
			(stroke
				(width 0.1524)
				(type default)
			)
			(layer "B.SilkS")
		)
		(fp_line
			(start 0.7874 0.4064)
			(end 0.7874 -0.4064)
			(stroke
				(width 0.1524)
				(type default)
			)
			(layer "B.SilkS")
		)
		(fp_line
			(start -0.7874 0.4064)
			(end 0.7874 0.4064)
			(stroke
				(width 0.1524)
				(type default)
			)
			(layer "B.SilkS")
		)
		(fp_line
			(start 0.67945 -0.305054)
			(end 0.12065 -0.305054)
			(stroke
				(width 0.1)
				(type default)
			)
			(layer "B.Fab")
		)
		(fp_line
			(start 0.12065 -0.305054)
			(end 0.12065 -0.2794)
			(stroke
				(width 0.1)
				(type default)
			)
			(layer "B.Fab")
		)
		(fp_line
			(start -0.12065 -0.3048)
			(end -0.67945 -0.3048)
			(stroke
				(width 0.1)
				(type default)
			)
			(layer "B.Fab")
		)
		(fp_line
			(start -0.67945 -0.3048)
			(end -0.67945 0.3048)
			(stroke
				(width 0.1)
				(type default)
			)
			(layer "B.Fab")
		)
		(fp_line
			(start 0.12065 -0.2794)
			(end -0.12065 -0.2794)
			(stroke
				(width 0.1)
				(type default)
			)
			(layer "B.Fab")
		)
		(fp_line
			(start -0.12065 -0.2794)
			(end -0.12065 -0.3048)
			(stroke
				(width 0.1)
				(type default)
			)
			(layer "B.Fab")
		)
		(fp_line
			(start 0.12065 0.2794)
			(end 0.12065 0.3048)
			(stroke
				(width 0.1)
				(type default)
			)
			(layer "B.Fab")
		)
		(fp_line
			(start -0.120396 0.2794)
			(end 0.12065 0.2794)
			(stroke
				(width 0.1)
				(type default)
			)
			(layer "B.Fab")
		)
		(fp_line
			(start 0.67945 0.3048)
			(end 0.67945 -0.305054)
			(stroke
				(width 0.1)
				(type default)
			)
			(layer "B.Fab")
		)
		(fp_line
			(start 0.12065 0.3048)
			(end 0.67945 0.3048)
			(stroke
				(width 0.1)
				(type default)
			)
			(layer "B.Fab")
		)
		(fp_line
			(start -0.120396 0.3048)
			(end -0.120396 0.2794)
			(stroke
				(width 0.1)
				(type default)
			)
			(layer "B.Fab")
		)
		(fp_line
			(start -0.67945 0.3048)
			(end -0.120396 0.3048)
			(stroke
				(width 0.1)
				(type default)
			)
			(layer "B.Fab")
		)
		(pad "1" smd circle
			(at 0.40005 0 270)
			(size 0 0)
			(layers "B.Cu" "B.Mask" "B.Paste")
			(net "I3C_MUX_CPU0_VIO")
		)
		(pad "2" smd circle
			(at -0.40005 0 270)
			(size 0 0)
			(layers "B.Cu" "B.Mask" "B.Paste")
			(net "GND")
		)
	)
)
